(kicad_pcb
	(version 20260206)
	(generator "pcbnew")
	(generator_version "10.0")
	(general
		(thickness 1.6)
		(legacy_teardrops no)
	)
	(paper "A4")
	(title_block
		(title "04192023_DAF0TMB3IC0_F0TG_MB_C_brd_V02_OCP.brd")
		(comment 1 "Grand Teton / footprints 492-495 of 8354")
	)
	(layers
		(0 "F.Cu" signal "TOP")
		(4 "In1.Cu" signal "GND")
		(6 "In2.Cu" signal "IN1")
		(8 "In3.Cu" signal "GND1")
		(10 "In4.Cu" signal "IN2")
		(12 "In5.Cu" signal "GND2")
		(14 "In6.Cu" signal "IN3")
		(16 "In7.Cu" signal "GND3")
		(18 "In8.Cu" signal "VCC")
		(20 "In9.Cu" signal "VCC1")
		(22 "In10.Cu" signal "GND4")
		(24 "In11.Cu" signal "IN4")
		(26 "In12.Cu" signal "GND5")
		(28 "In13.Cu" signal "IN5")
		(30 "In14.Cu" signal "GND6")
		(32 "In15.Cu" signal "IN6")
		(34 "In16.Cu" signal "GND7")
		(2 "B.Cu" signal "BOTTOM")
		(9 "F.Adhes" user "F.Adhesive")
		(11 "B.Adhes" user "B.Adhesive")
		(13 "F.Paste" user "Package Geometry/Pastemask Top")
		(15 "B.Paste" user "Package Geometry/Pastemask Bottom")
		(5 "F.SilkS" user "Ref Des/Silkscreen Top")
		(7 "B.SilkS" user "Ref Des/Silkscreen Bottom")
		(1 "F.Mask" user "Board Geometry/Soldermask Top")
		(3 "B.Mask" user "Board Geometry/Soldermask Bottom")
		(17 "Dwgs.User" user "User.Drawings")
		(19 "Cmts.User" user "User.Comments")
		(21 "Eco1.User" user "User.Eco1")
		(23 "Eco2.User" user "User.Eco2")
		(25 "Edge.Cuts" user "Board Geometry/Outline")
		(27 "Margin" user)
		(31 "F.CrtYd" user "Package Geometry/Place Bound Top")
		(29 "B.CrtYd" user "Package Geometry/Place Bound Bottom")
		(35 "F.Fab" user "Ref Des/Assembly Top")
		(33 "B.Fab" user "Ref Des/Assembly Bottom")
	)
	(footprint ""
		(layer "F.Cu")
		(at 40.6527 -102.5525 90)
		(property "Reference" "U57"
			(at -1.4224 -1.844548 90)
			(unlocked yes)
			(layer "F.SilkS")
			(effects
				(font
					(size 0.7874 0.5842)
					(thickness 0.1524)
				)
				(justify left)
			)
		)
		(property "Value" ""
			(at 0 0 90)
			(layer "F.Fab")
			(effects
				(font
					(size 1.27 1.27)
				)
			)
		)
		(duplicate_pad_numbers_are_jumpers no)
		(fp_line
			(start 1.335278 -1.100074)
			(end -1.335278 -1.100074)
			(stroke
				(width 0.1524)
				(type default)
			)
			(layer "F.SilkS")
		)
		(fp_line
			(start -1.335278 -1.100074)
			(end -1.335278 1.100074)
			(stroke
				(width 0.1524)
				(type default)
			)
			(layer "F.SilkS")
		)
		(fp_line
			(start 1.335278 1.100074)
			(end 1.335278 -1.100074)
			(stroke
				(width 0.1524)
				(type default)
			)
			(layer "F.SilkS")
		)
		(fp_line
			(start -1.335278 1.100074)
			(end 1.335278 1.100074)
			(stroke
				(width 0.1524)
				(type default)
			)
			(layer "F.SilkS")
		)
		(fp_line
			(start 0.674878 -1.100074)
			(end -0.674878 -1.100074)
			(stroke
				(width 0.1)
				(type default)
			)
			(layer "F.Fab")
		)
		(fp_line
			(start -0.674878 -1.100074)
			(end -0.674878 1.100074)
			(stroke
				(width 0.1)
				(type default)
			)
			(layer "F.Fab")
		)
		(fp_line
			(start 0.674878 1.100074)
			(end 0.674878 -1.100074)
			(stroke
				(width 0.1)
				(type default)
			)
			(layer "F.Fab")
		)
		(fp_line
			(start -0.674878 1.100074)
			(end 0.674878 1.100074)
			(stroke
				(width 0.1)
				(type default)
			)
			(layer "F.Fab")
		)
		(pad "1" smd rect
			(at -0.8001 0.649986)
			(size 0.6096 0.8128)
			(layers "F.Cu" "F.Mask" "F.Paste")
			(net "P12V_AUX_DSC_VOL")
		)
		(pad "2" smd rect
			(at -0.8001 -0.649986)
			(size 0.6096 0.8128)
			(layers "F.Cu" "F.Mask" "F.Paste")
			(net "Net_10857")
		)
		(pad "3" smd rect
			(at 0.8001 0)
			(size 0.6096 0.8128)
			(layers "F.Cu" "F.Mask" "F.Paste")
			(net "P12V_AUX_DSC_S1")
		)
	)
	(footprint ""
		(layer "F.Cu")
		(at 289.012884 -370.318792 -90)
		(property "Reference" "C8066"
			(at 0 0 270)
			(layer "F.SilkS")
			(hide yes)
			(effects
				(font
					(size 1.27 1.27)
				)
			)
		)
		(property "Value" ""
			(at 0 0 270)
			(layer "F.Fab")
			(effects
				(font
					(size 1.27 1.27)
				)
			)
		)
		(duplicate_pad_numbers_are_jumpers no)
		(fp_line
			(start -0.7874 0.4064)
			(end -0.7874 -0.4064)
			(stroke
				(width 0.1524)
				(type default)
			)
			(layer "F.SilkS")
		)
		(fp_line
			(start 0.7874 0.4064)
			(end -0.7874 0.4064)
			(stroke
				(width 0.1524)
				(type default)
			)
			(layer "F.SilkS")
		)
		(fp_line
			(start -0.7874 -0.4064)
			(end 0.7874 -0.4064)
			(stroke
				(width 0.1524)
				(type default)
			)
			(layer "F.SilkS")
		)
		(fp_line
			(start 0.7874 -0.4064)
			(end 0.7874 0.4064)
			(stroke
				(width 0.1524)
				(type default)
			)
			(layer "F.SilkS")
		)
		(fp_line
			(start -0.67945 0.3048)
			(end -0.67945 -0.305054)
			(stroke
				(width 0.1)
				(type default)
			)
			(layer "F.Fab")
		)
		(fp_line
			(start -0.12065 0.3048)
			(end -0.67945 0.3048)
			(stroke
				(width 0.1)
				(type default)
			)
			(layer "F.Fab")
		)
		(fp_line
			(start 0.120396 0.3048)
			(end 0.120396 0.2794)
			(stroke
				(width 0.1)
				(type default)
			)
			(layer "F.Fab")
		)
		(fp_line
			(start 0.67945 0.3048)
			(end 0.120396 0.3048)
			(stroke
				(width 0.1)
				(type default)
			)
			(layer "F.Fab")
		)
		(fp_line
			(start -0.12065 0.2794)
			(end -0.12065 0.3048)
			(stroke
				(width 0.1)
				(type default)
			)
			(layer "F.Fab")
		)
		(fp_line
			(start 0.120396 0.2794)
			(end -0.12065 0.2794)
			(stroke
				(width 0.1)
				(type default)
			)
			(layer "F.Fab")
		)
		(fp_line
			(start -0.12065 -0.2794)
			(end 0.12065 -0.2794)
			(stroke
				(width 0.1)
				(type default)
			)
			(layer "F.Fab")
		)
		(fp_line
			(start 0.12065 -0.2794)
			(end 0.12065 -0.3048)
			(stroke
				(width 0.1)
				(type default)
			)
			(layer "F.Fab")
		)
		(fp_line
			(start 0.12065 -0.3048)
			(end 0.67945 -0.3048)
			(stroke
				(width 0.1)
				(type default)
			)
			(layer "F.Fab")
		)
		(fp_line
			(start 0.67945 -0.3048)
			(end 0.67945 0.3048)
			(stroke
				(width 0.1)
				(type default)
			)
			(layer "F.Fab")
		)
		(fp_line
			(start -0.67945 -0.305054)
			(end -0.12065 -0.305054)
			(stroke
				(width 0.1)
				(type default)
			)
			(layer "F.Fab")
		)
		(fp_line
			(start -0.12065 -0.305054)
			(end -0.12065 -0.2794)
			(stroke
				(width 0.1)
				(type default)
			)
			(layer "F.Fab")
		)
		(pad "1" smd circle
			(at -0.40005 0 270)
			(size 0 0)
			(layers "F.Cu" "F.Mask" "F.Paste")
			(net "PVDDIO_P0_EN_R")
		)
		(pad "2" smd circle
			(at 0.40005 0 270)
			(size 0 0)
			(layers "F.Cu" "F.Mask" "F.Paste")
			(net "GND")
		)
	)
	(footprint ""
		(layer "F.Cu")
		(at 325.862188 -392.48588 180)
		(property "Reference" "R952"
			(at 0 0 180)
			(layer "F.SilkS")
			(hide yes)
			(effects
				(font
					(size 1.27 1.27)
				)
			)
		)
		(property "Value" ""
			(at 0 0 180)
			(layer "F.Fab")
			(effects
				(font
					(size 1.27 1.27)
				)
			)
		)
		(duplicate_pad_numbers_are_jumpers no)
		(fp_line
			(start 0.7874 0.4064)
			(end -0.7874 0.4064)
			(stroke
				(width 0.1524)
				(type default)
			)
			(layer "F.SilkS")
		)
		(fp_line
			(start 0.7874 -0.4064)
			(end 0.7874 0.4064)
			(stroke
				(width 0.1524)
				(type default)
			)
			(layer "F.SilkS")
		)
		(fp_line
			(start -0.7874 0.4064)
			(end -0.7874 -0.4064)
			(stroke
				(width 0.1524)
				(type default)
			)
			(layer "F.SilkS")
		)
		(fp_line
			(start -0.7874 -0.4064)
			(end 0.7874 -0.4064)
			(stroke
				(width 0.1524)
				(type default)
			)
			(layer "F.SilkS")
		)
		(fp_line
			(start 0.67945 0.3048)
			(end 0.120396 0.3048)
			(stroke
				(width 0.1)
				(type default)
			)
			(layer "F.Fab")
		)
		(fp_line
			(start 0.67945 -0.3048)
			(end 0.67945 0.3048)
			(stroke
				(width 0.1)
				(type default)
			)
			(layer "F.Fab")
		)
		(fp_line
			(start 0.12065 -0.2794)
			(end 0.12065 -0.3048)
			(stroke
				(width 0.1)
				(type default)
			)
			(layer "F.Fab")
		)
		(fp_line
			(start 0.12065 -0.3048)
			(end 0.67945 -0.3048)
			(stroke
				(width 0.1)
				(type default)
			)
			(layer "F.Fab")
		)
		(fp_line
			(start 0.120396 0.3048)
			(end 0.120396 0.2794)
			(stroke
				(width 0.1)
				(type default)
			)
			(layer "F.Fab")
		)
		(fp_line
			(start 0.120396 0.2794)
			(end -0.12065 0.2794)
			(stroke
				(width 0.1)
				(type default)
			)
			(layer "F.Fab")
		)
		(fp_line
			(start -0.12065 0.3048)
			(end -0.67945 0.3048)
			(stroke
				(width 0.1)
				(type default)
			)
			(layer "F.Fab")
		)
		(fp_line
			(start -0.12065 0.2794)
			(end -0.12065 0.3048)
			(stroke
				(width 0.1)
				(type default)
			)
			(layer "F.Fab")
		)
		(fp_line
			(start -0.12065 -0.2794)
			(end 0.12065 -0.2794)
			(stroke
				(width 0.1)
				(type default)
			)
			(layer "F.Fab")
		)
		(fp_line
			(start -0.12065 -0.305054)
			(end -0.12065 -0.2794)
			(stroke
				(width 0.1)
				(type default)
			)
			(layer "F.Fab")
		)
		(fp_line
			(start -0.67945 0.3048)
			(end -0.67945 -0.305054)
			(stroke
				(width 0.1)
				(type default)
			)
			(layer "F.Fab")
		)
		(fp_line
			(start -0.67945 -0.305054)
			(end -0.12065 -0.305054)
			(stroke
				(width 0.1)
				(type default)
			)
			(layer "F.Fab")
		)
		(pad "1" smd rect
			(at -0.40005 0)
			(size 0.4572 0.508)
			(layers "F.Cu" "F.Mask" "F.Paste")
			(net "P1V8_CPU0_RT0_1A_1D")
		)
		(pad "2" smd rect
			(at 0.40005 0)
			(size 0.4572 0.508)
			(layers "F.Cu" "F.Mask" "F.Paste")
			(net "P1V8_CPU0_RT0_1A")
		)
	)
	(footprint ""
		(layer "F.Cu")
		(at 10.066782 -406.119584 180)
		(property "Reference" "PC6544"
			(at 0 0 180)
			(layer "F.SilkS")
			(hide yes)
			(effects
				(font
					(size 1.27 1.27)
				)
			)
		)
		(property "Value" ""
			(at 0 0 180)
			(layer "F.Fab")
			(effects
				(font
					(size 1.27 1.27)
				)
			)
		)
		(duplicate_pad_numbers_are_jumpers no)
		(fp_line
			(start 0.7874 0.4064)
			(end -0.7874 0.4064)
			(stroke
				(width 0.1524)
				(type default)
			)
			(layer "F.SilkS")
		)
		(fp_line
			(start 0.7874 -0.4064)
			(end 0.7874 0.4064)
			(stroke
				(width 0.1524)
				(type default)
			)
			(layer "F.SilkS")
		)
		(fp_line
			(start -0.7874 0.4064)
			(end -0.7874 -0.4064)
			(stroke
				(width 0.1524)
				(type default)
			)
			(layer "F.SilkS")
		)
		(fp_line
			(start -0.7874 -0.4064)
			(end 0.7874 -0.4064)
			(stroke
				(width 0.1524)
				(type default)
			)
			(layer "F.SilkS")
		)
		(fp_line
			(start 0.67945 0.3048)
			(end 0.120396 0.3048)
			(stroke
				(width 0.1)
				(type default)
			)
			(layer "F.Fab")
		)
		(fp_line
			(start 0.67945 -0.3048)
			(end 0.67945 0.3048)
			(stroke
				(width 0.1)
				(type default)
			)
			(layer "F.Fab")
		)
		(fp_line
			(start 0.12065 -0.2794)
			(end 0.12065 -0.3048)
			(stroke
				(width 0.1)
				(type default)
			)
			(layer "F.Fab")
		)
		(fp_line
			(start 0.12065 -0.3048)
			(end 0.67945 -0.3048)
			(stroke
				(width 0.1)
				(type default)
			)
			(layer "F.Fab")
		)
		(fp_line
			(start 0.120396 0.3048)
			(end 0.120396 0.2794)
			(stroke
				(width 0.1)
				(type default)
			)
			(layer "F.Fab")
		)
		(fp_line
			(start 0.120396 0.2794)
			(end -0.12065 0.2794)
			(stroke
				(width 0.1)
				(type default)
			)
			(layer "F.Fab")
		)
		(fp_line
			(start -0.12065 0.3048)
			(end -0.67945 0.3048)
			(stroke
				(width 0.1)
				(type default)
			)
			(layer "F.Fab")
		)
		(fp_line
			(start -0.12065 0.2794)
			(end -0.12065 0.3048)
			(stroke
				(width 0.1)
				(type default)
			)
			(layer "F.Fab")
		)
		(fp_line
			(start -0.12065 -0.2794)
			(end 0.12065 -0.2794)
			(stroke
				(width 0.1)
				(type default)
			)
			(layer "F.Fab")
		)
		(fp_line
			(start -0.12065 -0.305054)
			(end -0.12065 -0.2794)
			(stroke
				(width 0.1)
				(type default)
			)
			(layer "F.Fab")
		)
		(fp_line
			(start -0.67945 0.3048)
			(end -0.67945 -0.305054)
			(stroke
				(width 0.1)
				(type default)
			)
			(layer "F.Fab")
		)
		(fp_line
			(start -0.67945 -0.305054)
			(end -0.12065 -0.305054)
			(stroke
				(width 0.1)
				(type default)
			)
			(layer "F.Fab")
		)
		(pad "1" smd circle
			(at -0.40005 0 180)
			(size 0 0)
			(layers "F.Cu" "F.Mask" "F.Paste")
			(net "P0V9_RETIMER_CPU1_VCC")
		)
		(pad "2" smd circle
			(at 0.40005 0 180)
			(size 0 0)
			(layers "F.Cu" "F.Mask" "F.Paste")
			(net "GND")
		)
	)
)
